(kicad_pcb
	(version 20260206)
	(generator "pcbnew")
	(generator_version "10.0")
	(general
		(thickness 1.6)
		(legacy_teardrops no)
	)
	(paper "A4")
	(title_block
		(title "03242023_DA0F0TMBIJ0_F0T_Motherboard_J_brd_V01_OCP.brd")
		(comment 1 "Grand Teton / footprints 3679-3685 of 6105")
	)
	(layers
		(0 "F.Cu" signal "TOP")
		(4 "In1.Cu" signal "GND")
		(6 "In2.Cu" signal "IN1")
		(8 "In3.Cu" signal "GND1")
		(10 "In4.Cu" signal "IN2")
		(12 "In5.Cu" signal "GND2")
		(14 "In6.Cu" signal "IN3")
		(16 "In7.Cu" signal "GND3")
		(18 "In8.Cu" signal "VCC")
		(20 "In9.Cu" signal "VCC1")
		(22 "In10.Cu" signal "GND4")
		(24 "In11.Cu" signal "IN4")
		(26 "In12.Cu" signal "GND5")
		(28 "In13.Cu" signal "IN5")
		(30 "In14.Cu" signal "GND6")
		(32 "In15.Cu" signal "IN6")
		(34 "In16.Cu" signal "GND7")
		(2 "B.Cu" signal "BOTTOM")
		(9 "F.Adhes" user "F.Adhesive")
		(11 "B.Adhes" user "B.Adhesive")
		(13 "F.Paste" user "Package Geometry/Pastemask Top")
		(15 "B.Paste" user "Package Geometry/Pastemask Bottom")
		(5 "F.SilkS" user "Ref Des/Silkscreen Top")
		(7 "B.SilkS" user "Ref Des/Silkscreen Bottom")
		(1 "F.Mask" user "Board Geometry/Soldermask Top")
		(3 "B.Mask" user "Board Geometry/Soldermask Bottom")
		(17 "Dwgs.User" user "User.Drawings")
		(19 "Cmts.User" user "User.Comments")
		(21 "Eco1.User" user "User.Eco1")
		(23 "Eco2.User" user "User.Eco2")
		(25 "Edge.Cuts" user "Board Geometry/Outline")
		(27 "Margin" user)
		(31 "F.CrtYd" user "Package Geometry/Place Bound Top")
		(29 "B.CrtYd" user "Package Geometry/Place Bound Bottom")
		(35 "F.Fab" user "Ref Des/Assembly Top")
		(33 "B.Fab" user "Ref Des/Assembly Bottom")
	)
	(footprint ""
		(layer "F.Cu")
		(at 424.557444 -367.231676)
		(property "Reference" "PR1298"
			(at 0 0 0)
			(layer "F.SilkS")
			(hide yes)
			(effects
				(font
					(size 1.27 1.27)
				)
			)
		)
		(property "Value" ""
			(at 0 0 0)
			(layer "F.Fab")
			(effects
				(font
					(size 1.27 1.27)
				)
			)
		)
		(duplicate_pad_numbers_are_jumpers no)
		(fp_line
			(start -0.7874 -0.4064)
			(end 0.7874 -0.4064)
			(stroke
				(width 0.1524)
				(type default)
			)
			(layer "F.SilkS")
		)
		(fp_line
			(start -0.7874 0.4064)
			(end -0.7874 -0.4064)
			(stroke
				(width 0.1524)
				(type default)
			)
			(layer "F.SilkS")
		)
		(fp_line
			(start 0.7874 -0.4064)
			(end 0.7874 0.4064)
			(stroke
				(width 0.1524)
				(type default)
			)
			(layer "F.SilkS")
		)
		(fp_line
			(start 0.7874 0.4064)
			(end -0.7874 0.4064)
			(stroke
				(width 0.1524)
				(type default)
			)
			(layer "F.SilkS")
		)
		(fp_line
			(start -0.67945 -0.305054)
			(end -0.12065 -0.305054)
			(stroke
				(width 0.1)
				(type default)
			)
			(layer "F.Fab")
		)
		(fp_line
			(start -0.67945 0.3048)
			(end -0.67945 -0.305054)
			(stroke
				(width 0.1)
				(type default)
			)
			(layer "F.Fab")
		)
		(fp_line
			(start -0.12065 -0.305054)
			(end -0.12065 -0.2794)
			(stroke
				(width 0.1)
				(type default)
			)
			(layer "F.Fab")
		)
		(fp_line
			(start -0.12065 -0.2794)
			(end 0.12065 -0.2794)
			(stroke
				(width 0.1)
				(type default)
			)
			(layer "F.Fab")
		)
		(fp_line
			(start -0.12065 0.2794)
			(end -0.12065 0.3048)
			(stroke
				(width 0.1)
				(type default)
			)
			(layer "F.Fab")
		)
		(fp_line
			(start -0.12065 0.3048)
			(end -0.67945 0.3048)
			(stroke
				(width 0.1)
				(type default)
			)
			(layer "F.Fab")
		)
		(fp_line
			(start 0.120396 0.2794)
			(end -0.12065 0.2794)
			(stroke
				(width 0.1)
				(type default)
			)
			(layer "F.Fab")
		)
		(fp_line
			(start 0.120396 0.3048)
			(end 0.120396 0.2794)
			(stroke
				(width 0.1)
				(type default)
			)
			(layer "F.Fab")
		)
		(fp_line
			(start 0.12065 -0.3048)
			(end 0.67945 -0.3048)
			(stroke
				(width 0.1)
				(type default)
			)
			(layer "F.Fab")
		)
		(fp_line
			(start 0.12065 -0.2794)
			(end 0.12065 -0.3048)
			(stroke
				(width 0.1)
				(type default)
			)
			(layer "F.Fab")
		)
		(fp_line
			(start 0.67945 -0.3048)
			(end 0.67945 0.3048)
			(stroke
				(width 0.1)
				(type default)
			)
			(layer "F.Fab")
		)
		(fp_line
			(start 0.67945 0.3048)
			(end 0.120396 0.3048)
			(stroke
				(width 0.1)
				(type default)
			)
			(layer "F.Fab")
		)
		(pad "1" smd circle
			(at -0.40005 0)
			(size 0 0)
			(layers "F.Cu" "F.Mask" "F.Paste")
			(net "PVCCFA_EHV_FIVRA_CPU0_LSET3")
		)
		(pad "2" smd circle
			(at 0.40005 0)
			(size 0 0)
			(layers "F.Cu" "F.Mask" "F.Paste")
			(net "GND")
		)
	)
	(footprint ""
		(layer "F.Cu")
		(at 175.595534 -353.62261 -90)
		(property "Reference" "PC399_P1_1"
			(at 0 0 270)
			(layer "F.SilkS")
			(hide yes)
			(effects
				(font
					(size 1.27 1.27)
				)
			)
		)
		(property "Value" ""
			(at 0 0 270)
			(layer "F.Fab")
			(effects
				(font
					(size 1.27 1.27)
				)
			)
		)
		(duplicate_pad_numbers_are_jumpers no)
		(fp_line
			(start -0.7874 0.4064)
			(end -0.7874 -0.4064)
			(stroke
				(width 0.1524)
				(type default)
			)
			(layer "F.SilkS")
		)
		(fp_line
			(start 0.7874 0.4064)
			(end -0.7874 0.4064)
			(stroke
				(width 0.1524)
				(type default)
			)
			(layer "F.SilkS")
		)
		(fp_line
			(start -0.7874 -0.4064)
			(end 0.7874 -0.4064)
			(stroke
				(width 0.1524)
				(type default)
			)
			(layer "F.SilkS")
		)
		(fp_line
			(start 0.7874 -0.4064)
			(end 0.7874 0.4064)
			(stroke
				(width 0.1524)
				(type default)
			)
			(layer "F.SilkS")
		)
		(fp_line
			(start -0.67945 0.3048)
			(end -0.67945 -0.305054)
			(stroke
				(width 0.1)
				(type default)
			)
			(layer "F.Fab")
		)
		(fp_line
			(start -0.12065 0.3048)
			(end -0.67945 0.3048)
			(stroke
				(width 0.1)
				(type default)
			)
			(layer "F.Fab")
		)
		(fp_line
			(start 0.120396 0.3048)
			(end 0.120396 0.2794)
			(stroke
				(width 0.1)
				(type default)
			)
			(layer "F.Fab")
		)
		(fp_line
			(start 0.67945 0.3048)
			(end 0.120396 0.3048)
			(stroke
				(width 0.1)
				(type default)
			)
			(layer "F.Fab")
		)
		(fp_line
			(start -0.12065 0.2794)
			(end -0.12065 0.3048)
			(stroke
				(width 0.1)
				(type default)
			)
			(layer "F.Fab")
		)
		(fp_line
			(start 0.120396 0.2794)
			(end -0.12065 0.2794)
			(stroke
				(width 0.1)
				(type default)
			)
			(layer "F.Fab")
		)
		(fp_line
			(start -0.12065 -0.2794)
			(end 0.12065 -0.2794)
			(stroke
				(width 0.1)
				(type default)
			)
			(layer "F.Fab")
		)
		(fp_line
			(start 0.12065 -0.2794)
			(end 0.12065 -0.3048)
			(stroke
				(width 0.1)
				(type default)
			)
			(layer "F.Fab")
		)
		(fp_line
			(start 0.12065 -0.3048)
			(end 0.67945 -0.3048)
			(stroke
				(width 0.1)
				(type default)
			)
			(layer "F.Fab")
		)
		(fp_line
			(start 0.67945 -0.3048)
			(end 0.67945 0.3048)
			(stroke
				(width 0.1)
				(type default)
			)
			(layer "F.Fab")
		)
		(fp_line
			(start -0.67945 -0.305054)
			(end -0.12065 -0.305054)
			(stroke
				(width 0.1)
				(type default)
			)
			(layer "F.Fab")
		)
		(fp_line
			(start -0.12065 -0.305054)
			(end -0.12065 -0.2794)
			(stroke
				(width 0.1)
				(type default)
			)
			(layer "F.Fab")
		)
		(pad "1" smd circle
			(at -0.40005 0 270)
			(size 0 0)
			(layers "F.Cu" "F.Mask" "F.Paste")
			(net "SW_P12V_PVCCFA_EHV_FIVRA_CPU1_R")
		)
		(pad "2" smd circle
			(at 0.40005 0 270)
			(size 0 0)
			(layers "F.Cu" "F.Mask" "F.Paste")
			(net "GND")
		)
	)
	(footprint ""
		(layer "F.Cu")
		(at 385.716272 -58.703464 180)
		(property "Reference" "R1472"
			(at 0 0 180)
			(layer "F.SilkS")
			(hide yes)
			(effects
				(font
					(size 1.27 1.27)
				)
			)
		)
		(property "Value" ""
			(at 0 0 180)
			(layer "F.Fab")
			(effects
				(font
					(size 1.27 1.27)
				)
			)
		)
		(duplicate_pad_numbers_are_jumpers no)
		(fp_line
			(start 0.7874 0.4064)
			(end -0.7874 0.4064)
			(stroke
				(width 0.1524)
				(type default)
			)
			(layer "F.SilkS")
		)
		(fp_line
			(start 0.7874 -0.4064)
			(end 0.7874 0.4064)
			(stroke
				(width 0.1524)
				(type default)
			)
			(layer "F.SilkS")
		)
		(fp_line
			(start -0.7874 0.4064)
			(end -0.7874 -0.4064)
			(stroke
				(width 0.1524)
				(type default)
			)
			(layer "F.SilkS")
		)
		(fp_line
			(start -0.7874 -0.4064)
			(end 0.7874 -0.4064)
			(stroke
				(width 0.1524)
				(type default)
			)
			(layer "F.SilkS")
		)
		(fp_line
			(start 0.67945 0.3048)
			(end 0.120396 0.3048)
			(stroke
				(width 0.1)
				(type default)
			)
			(layer "F.Fab")
		)
		(fp_line
			(start 0.67945 -0.3048)
			(end 0.67945 0.3048)
			(stroke
				(width 0.1)
				(type default)
			)
			(layer "F.Fab")
		)
		(fp_line
			(start 0.12065 -0.2794)
			(end 0.12065 -0.3048)
			(stroke
				(width 0.1)
				(type default)
			)
			(layer "F.Fab")
		)
		(fp_line
			(start 0.12065 -0.3048)
			(end 0.67945 -0.3048)
			(stroke
				(width 0.1)
				(type default)
			)
			(layer "F.Fab")
		)
		(fp_line
			(start 0.120396 0.3048)
			(end 0.120396 0.2794)
			(stroke
				(width 0.1)
				(type default)
			)
			(layer "F.Fab")
		)
		(fp_line
			(start 0.120396 0.2794)
			(end -0.12065 0.2794)
			(stroke
				(width 0.1)
				(type default)
			)
			(layer "F.Fab")
		)
		(fp_line
			(start -0.12065 0.3048)
			(end -0.67945 0.3048)
			(stroke
				(width 0.1)
				(type default)
			)
			(layer "F.Fab")
		)
		(fp_line
			(start -0.12065 0.2794)
			(end -0.12065 0.3048)
			(stroke
				(width 0.1)
				(type default)
			)
			(layer "F.Fab")
		)
		(fp_line
			(start -0.12065 -0.2794)
			(end 0.12065 -0.2794)
			(stroke
				(width 0.1)
				(type default)
			)
			(layer "F.Fab")
		)
		(fp_line
			(start -0.12065 -0.305054)
			(end -0.12065 -0.2794)
			(stroke
				(width 0.1)
				(type default)
			)
			(layer "F.Fab")
		)
		(fp_line
			(start -0.67945 0.3048)
			(end -0.67945 -0.305054)
			(stroke
				(width 0.1)
				(type default)
			)
			(layer "F.Fab")
		)
		(fp_line
			(start -0.67945 -0.305054)
			(end -0.12065 -0.305054)
			(stroke
				(width 0.1)
				(type default)
			)
			(layer "F.Fab")
		)
		(pad "1" smd circle
			(at -0.40005 0 180)
			(size 0 0)
			(layers "F.Cu" "F.Mask" "F.Paste")
			(net "JTAG_DBP_PRESENT_R_N")
		)
		(pad "2" smd circle
			(at 0.40005 0 180)
			(size 0 0)
			(layers "F.Cu" "F.Mask" "F.Paste")
			(net "FM_BMC_DBP_PRESENT_R_N")
		)
	)
	(footprint ""
		(layer "F.Cu")
		(at 72.460358 -402.371052 -90)
		(property "Reference" "C726"
			(at 0 0 270)
			(layer "F.SilkS")
			(hide yes)
			(effects
				(font
					(size 1.27 1.27)
				)
			)
		)
		(property "Value" ""
			(at 0 0 270)
			(layer "F.Fab")
			(effects
				(font
					(size 1.27 1.27)
				)
			)
		)
		(duplicate_pad_numbers_are_jumpers no)
		(fp_line
			(start -0.299974 0.150114)
			(end -0.299974 -0.150114)
			(stroke
				(width 0.1)
				(type default)
			)
			(layer "F.Fab")
		)
		(fp_line
			(start 0.299974 0.150114)
			(end -0.299974 0.150114)
			(stroke
				(width 0.1)
				(type default)
			)
			(layer "F.Fab")
		)
		(fp_line
			(start -0.299974 -0.150114)
			(end 0.299974 -0.150114)
			(stroke
				(width 0.1)
				(type default)
			)
			(layer "F.Fab")
		)
		(fp_line
			(start 0.299974 -0.150114)
			(end 0.299974 0.150114)
			(stroke
				(width 0.1)
				(type default)
			)
			(layer "F.Fab")
		)
		(pad "1" smd rect
			(at -0.2667 0 270)
			(size 0.3048 0.381)
			(layers "F.Cu" "F.Mask" "F.Paste")
			(net "P5E_CPU1_PE0_TX_C_DN<7>")
		)
		(pad "2" smd rect
			(at 0.2667 0 270)
			(size 0.3048 0.381)
			(layers "F.Cu" "F.Mask" "F.Paste")
			(net "P5E_CPU1_PE0_TX_DN<7>")
		)
	)
	(footprint ""
		(layer "F.Cu")
		(at 420.591488 -165.018974 180)
		(property "Reference" "PC1354"
			(at 0 0 180)
			(layer "F.SilkS")
			(hide yes)
			(effects
				(font
					(size 1.27 1.27)
				)
			)
		)
		(property "Value" ""
			(at 0 0 180)
			(layer "F.Fab")
			(effects
				(font
					(size 1.27 1.27)
				)
			)
		)
		(duplicate_pad_numbers_are_jumpers no)
		(fp_line
			(start 0.7874 0.4064)
			(end -0.7874 0.4064)
			(stroke
				(width 0.1524)
				(type default)
			)
			(layer "F.SilkS")
		)
		(fp_line
			(start 0.7874 -0.4064)
			(end 0.7874 0.4064)
			(stroke
				(width 0.1524)
				(type default)
			)
			(layer "F.SilkS")
		)
		(fp_line
			(start -0.7874 0.4064)
			(end -0.7874 -0.4064)
			(stroke
				(width 0.1524)
				(type default)
			)
			(layer "F.SilkS")
		)
		(fp_line
			(start -0.7874 -0.4064)
			(end 0.7874 -0.4064)
			(stroke
				(width 0.1524)
				(type default)
			)
			(layer "F.SilkS")
		)
		(fp_line
			(start 0.67945 0.3048)
			(end 0.120396 0.3048)
			(stroke
				(width 0.1)
				(type default)
			)
			(layer "F.Fab")
		)
		(fp_line
			(start 0.67945 -0.3048)
			(end 0.67945 0.3048)
			(stroke
				(width 0.1)
				(type default)
			)
			(layer "F.Fab")
		)
		(fp_line
			(start 0.12065 -0.2794)
			(end 0.12065 -0.3048)
			(stroke
				(width 0.1)
				(type default)
			)
			(layer "F.Fab")
		)
		(fp_line
			(start 0.12065 -0.3048)
			(end 0.67945 -0.3048)
			(stroke
				(width 0.1)
				(type default)
			)
			(layer "F.Fab")
		)
		(fp_line
			(start 0.120396 0.3048)
			(end 0.120396 0.2794)
			(stroke
				(width 0.1)
				(type default)
			)
			(layer "F.Fab")
		)
		(fp_line
			(start 0.120396 0.2794)
			(end -0.12065 0.2794)
			(stroke
				(width 0.1)
				(type default)
			)
			(layer "F.Fab")
		)
		(fp_line
			(start -0.12065 0.3048)
			(end -0.67945 0.3048)
			(stroke
				(width 0.1)
				(type default)
			)
			(layer "F.Fab")
		)
		(fp_line
			(start -0.12065 0.2794)
			(end -0.12065 0.3048)
			(stroke
				(width 0.1)
				(type default)
			)
			(layer "F.Fab")
		)
		(fp_line
			(start -0.12065 -0.2794)
			(end 0.12065 -0.2794)
			(stroke
				(width 0.1)
				(type default)
			)
			(layer "F.Fab")
		)
		(fp_line
			(start -0.12065 -0.305054)
			(end -0.12065 -0.2794)
			(stroke
				(width 0.1)
				(type default)
			)
			(layer "F.Fab")
		)
		(fp_line
			(start -0.67945 0.3048)
			(end -0.67945 -0.305054)
			(stroke
				(width 0.1)
				(type default)
			)
			(layer "F.Fab")
		)
		(fp_line
			(start -0.67945 -0.305054)
			(end -0.12065 -0.305054)
			(stroke
				(width 0.1)
				(type default)
			)
			(layer "F.Fab")
		)
		(pad "1" smd circle
			(at -0.40005 0 180)
			(size 0 0)
			(layers "F.Cu" "F.Mask" "F.Paste")
			(net "GND")
		)
		(pad "2" smd circle
			(at 0.40005 0 180)
			(size 0 0)
			(layers "F.Cu" "F.Mask" "F.Paste")
			(net "PVCCD_HV_CPU0_VREF")
		)
	)
	(footprint ""
		(layer "F.Cu")
		(at 294.045894 -413.05988)
		(property "Reference" "R4692"
			(at 0 0 0)
			(layer "F.SilkS")
			(hide yes)
			(effects
				(font
					(size 1.27 1.27)
				)
			)
		)
		(property "Value" ""
			(at 0 0 0)
			(layer "F.Fab")
			(effects
				(font
					(size 1.27 1.27)
				)
			)
		)
		(duplicate_pad_numbers_are_jumpers no)
		(fp_line
			(start -0.7874 -0.4064)
			(end 0.7874 -0.4064)
			(stroke
				(width 0.1524)
				(type default)
			)
			(layer "F.SilkS")
		)
		(fp_line
			(start -0.7874 0.4064)
			(end -0.7874 -0.4064)
			(stroke
				(width 0.1524)
				(type default)
			)
			(layer "F.SilkS")
		)
		(fp_line
			(start 0.7874 -0.4064)
			(end 0.7874 0.4064)
			(stroke
				(width 0.1524)
				(type default)
			)
			(layer "F.SilkS")
		)
		(fp_line
			(start 0.7874 0.4064)
			(end -0.7874 0.4064)
			(stroke
				(width 0.1524)
				(type default)
			)
			(layer "F.SilkS")
		)
		(fp_line
			(start -0.67945 -0.305054)
			(end -0.12065 -0.305054)
			(stroke
				(width 0.1)
				(type default)
			)
			(layer "F.Fab")
		)
		(fp_line
			(start -0.67945 0.3048)
			(end -0.67945 -0.305054)
			(stroke
				(width 0.1)
				(type default)
			)
			(layer "F.Fab")
		)
		(fp_line
			(start -0.12065 -0.305054)
			(end -0.12065 -0.2794)
			(stroke
				(width 0.1)
				(type default)
			)
			(layer "F.Fab")
		)
		(fp_line
			(start -0.12065 -0.2794)
			(end 0.12065 -0.2794)
			(stroke
				(width 0.1)
				(type default)
			)
			(layer "F.Fab")
		)
		(fp_line
			(start -0.12065 0.2794)
			(end -0.12065 0.3048)
			(stroke
				(width 0.1)
				(type default)
			)
			(layer "F.Fab")
		)
		(fp_line
			(start -0.12065 0.3048)
			(end -0.67945 0.3048)
			(stroke
				(width 0.1)
				(type default)
			)
			(layer "F.Fab")
		)
		(fp_line
			(start 0.120396 0.2794)
			(end -0.12065 0.2794)
			(stroke
				(width 0.1)
				(type default)
			)
			(layer "F.Fab")
		)
		(fp_line
			(start 0.120396 0.3048)
			(end 0.120396 0.2794)
			(stroke
				(width 0.1)
				(type default)
			)
			(layer "F.Fab")
		)
		(fp_line
			(start 0.12065 -0.3048)
			(end 0.67945 -0.3048)
			(stroke
				(width 0.1)
				(type default)
			)
			(layer "F.Fab")
		)
		(fp_line
			(start 0.12065 -0.2794)
			(end 0.12065 -0.3048)
			(stroke
				(width 0.1)
				(type default)
			)
			(layer "F.Fab")
		)
		(fp_line
			(start 0.67945 -0.3048)
			(end 0.67945 0.3048)
			(stroke
				(width 0.1)
				(type default)
			)
			(layer "F.Fab")
		)
		(fp_line
			(start 0.67945 0.3048)
			(end 0.120396 0.3048)
			(stroke
				(width 0.1)
				(type default)
			)
			(layer "F.Fab")
		)
		(pad "1" smd circle
			(at -0.40005 0)
			(size 0 0)
			(layers "F.Cu" "F.Mask" "F.Paste")
			(net "P3V3_AUX")
		)
		(pad "2" smd circle
			(at 0.40005 0)
			(size 0 0)
			(layers "F.Cu" "F.Mask" "F.Paste")
			(net "TP_HSC_TYPE_ADC_ALERT")
		)
	)
	(footprint ""
		(layer "F.Cu")
		(at 82.564478 -402.371052 -90)
		(property "Reference" "C733"
			(at 0 0 270)
			(layer "F.SilkS")
			(hide yes)
			(effects
				(font
					(size 1.27 1.27)
				)
			)
		)
		(property "Value" ""
			(at 0 0 270)
			(layer "F.Fab")
			(effects
				(font
					(size 1.27 1.27)
				)
			)
		)
		(duplicate_pad_numbers_are_jumpers no)
		(fp_line
			(start -0.299974 0.150114)
			(end -0.299974 -0.150114)
			(stroke
				(width 0.1)
				(type default)
			)
			(layer "F.Fab")
		)
		(fp_line
			(start 0.299974 0.150114)
			(end -0.299974 0.150114)
			(stroke
				(width 0.1)
				(type default)
			)
			(layer "F.Fab")
		)
		(fp_line
			(start -0.299974 -0.150114)
			(end 0.299974 -0.150114)
			(stroke
				(width 0.1)
				(type default)
			)
			(layer "F.Fab")
		)
		(fp_line
			(start 0.299974 -0.150114)
			(end 0.299974 0.150114)
			(stroke
				(width 0.1)
				(type default)
			)
			(layer "F.Fab")
		)
		(pad "1" smd rect
			(at -0.2667 0 270)
			(size 0.3048 0.381)
			(layers "F.Cu" "F.Mask" "F.Paste")
			(net "P5E_CPU1_PE0_TX_C_DP<4>")
		)
		(pad "2" smd rect
			(at 0.2667 0 270)
			(size 0.3048 0.381)
			(layers "F.Cu" "F.Mask" "F.Paste")
			(net "P5E_CPU1_PE0_TX_DP<4>")
		)
	)
)
